(kicad_pcb
	(version 20221018)
	(generator pcbnew)
	(general
    (thickness 0.908)
  )
	(paper "A4")
	(title_block
    (title "HDMI-MIPI Bridge")
    (date "2024-04-24")
    (rev "1.3.2")
		(comment 9 "footprints 71-77 of 121")
	)
	(layers
    (0 "F.Cu" signal)
    (1 "In1.Cu" signal)
    (2 "In2.Cu" signal)
    (31 "B.Cu" signal)
    (32 "B.Adhes" user "B.Adhesive")
    (33 "F.Adhes" user "F.Adhesive")
    (34 "B.Paste" user)
    (35 "F.Paste" user)
    (36 "B.SilkS" user "B.Silkscreen")
    (37 "F.SilkS" user "F.Silkscreen")
    (38 "B.Mask" user)
    (39 "F.Mask" user)
    (40 "Dwgs.User" user "User.Drawings")
    (41 "Cmts.User" user "User.Comments")
    (42 "Eco1.User" user "User.Eco1")
    (43 "Eco2.User" user "User.Eco2")
    (44 "Edge.Cuts" user)
    (45 "Margin" user)
    (46 "B.CrtYd" user "B.Courtyard")
    (47 "F.CrtYd" user "F.Courtyard")
    (48 "B.Fab" user)
    (49 "F.Fab" user)
  )
	(footprint "antmicro-footprints:SOT1069-2" (layer "F.Cu")
    (at 165.6 103.85)
    (property "Author" "Antmicro")
    (property "License" "Apache-2.0")
    (property "MPN" "PCA9517ATP")
    (property "Manufacturer" "NXP")
    (property "Sheetfile" "channel2.kicad_sch")
    (property "Sheetname" "Channel 2")
    (property "ki_description" "Level Translating I2C-Bus Repeater, 2 Inputs, 0.9 V to 5.5 V Supply, 50 mA Out, HWSON-8")
    (property "ki_keywords" "SMT, LEVEL-SHIFTER, IC, I2C")
    (attr smd)
    (fp_text reference "U6" (at 0.08 -2.36 180) (layer "F.SilkS")
        (effects (font (size 0.7 0.7) (thickness 0.15)) (justify left bottom))
    )
    (fp_text value "PCA9517ATP" (at -2.54 3.4544) (layer "F.Fab")
        (effects (font (size 0.7 0.7) (thickness 0.15)) (justify left bottom))
    )
    (fp_text user "." (at -3.101 -1.101 unlocked) (layer "F.SilkS") hide
        (effects (font (size 0.7 0.7) (thickness 0.15)) (justify left bottom))
    )
    (fp_text user "${REFERENCE}" (at -4.375 3.499) (layer "F.Fab") hide
        (effects (font (size 0.7 0.7) (thickness 0.15)) (justify left bottom))
    )
    (fp_text user "License: Apache-2.0" (at -4.375 5.9) (layer "F.Fab") hide
        (effects (font (size 0.7 0.7) (thickness 0.15)) (justify left bottom))
    )
    (fp_text user "Author: Antmicro" (at -4.375 4.7) (layer "F.Fab") hide
        (effects (font (size 0.7 0.7) (thickness 0.15)) (justify left bottom))
    )
    (fp_line (start -1.375 -2.226) (end 1.375 -2.226)
      (stroke (width 0.15) (type solid)) (layer "F.SilkS"))
    (fp_line (start -1.375 1.425) (end -1.375 -2.226)
      (stroke (width 0.15) (type solid)) (layer "F.SilkS"))
    (fp_line (start -0.577 2.224) (end -1.375 1.425)
      (stroke (width 0.15) (type solid)) (layer "F.SilkS"))
    (fp_line (start 1.375 -2.226) (end 1.375 2.224)
      (stroke (width 0.15) (type solid)) (layer "F.SilkS"))
    (fp_line (start 1.375 2.224) (end -0.577 2.224)
      (stroke (width 0.15) (type solid)) (layer "F.SilkS"))
    (fp_circle (center -1.3208 2.0836) (end -1.2708 2.0836)
      (stroke (width 0.15) (type solid)) (fill solid) (layer "F.SilkS"))
    (fp_line (start -1.13 -2) (end 1.12 -2)
      (stroke (width 0.05) (type solid)) (layer "F.CrtYd"))
    (fp_line (start -1.13 1.98) (end -1.13 -2)
      (stroke (width 0.05) (type solid)) (layer "F.CrtYd"))
    (fp_line (start 1.12 -2) (end 1.12 1.98)
      (stroke (width 0.05) (type solid)) (layer "F.CrtYd"))
    (fp_line (start 1.12 1.98) (end -1.13 1.98)
      (stroke (width 0.05) (type solid)) (layer "F.CrtYd"))
    (pad "1" smd rect (at -0.75 1.411) (size 0.25 0.625) (layers "F.Cu" "F.Paste" "F.Mask")
      (net 9 "+3V3") (pinfunction "Vref1") (pintype "power_in"))
    (pad "2" smd rect (at -0.25 1.411) (size 0.25 0.625) (layers "F.Cu" "F.Paste" "F.Mask")
      (net 112 "/Channel 2/HDMI2_DDC_SCL_3V3") (pinfunction "SCL1") (pintype "input"))
    (pad "3" smd rect (at 0.25 1.411) (size 0.25 0.625) (layers "F.Cu" "F.Paste" "F.Mask")
      (net 111 "/Channel 2/HDMI2_DDC_SDA_3V3") (pinfunction "SDA1") (pintype "bidirectional"))
    (pad "4" smd rect (at 0.75 1.411) (size 0.25 0.625) (layers "F.Cu" "F.Paste" "F.Mask")
      (net 2 "GND") (pinfunction "GND") (pintype "power_in"))
    (pad "5" smd rect (at 0.75 -1.414) (size 0.25 0.625) (layers "F.Cu" "F.Paste" "F.Mask")
      (net 122 "Net-(U6-EN)") (pinfunction "EN") (pintype "input"))
    (pad "6" smd rect (at 0.25 -1.414) (size 0.25 0.625) (layers "F.Cu" "F.Paste" "F.Mask")
      (net 140 "/Channel 2/HDMI2_DDC_SDA") (pinfunction "SDA2") (pintype "bidirectional"))
    (pad "7" smd rect (at -0.25 -1.414) (size 0.25 0.625) (layers "F.Cu" "F.Paste" "F.Mask")
      (net 139 "/Channel 2/HDMI2_DDC_SCL") (pinfunction "SCL2") (pintype "input"))
    (pad "8" smd rect (at -0.75 -1.414) (size 0.25 0.625) (layers "F.Cu" "F.Paste" "F.Mask")
      (net 14 "+5V") (pinfunction "Vref2") (pintype "power_in"))
    (pad "9" smd roundrect (at 0 0) (size 1.6 1.6) (layers "F.Cu" "F.Paste" "F.Mask") (roundrect_rratio 0.05)
      (net 2 "GND") (pinfunction "GND") (pintype "passive") (solder_paste_margin -0.05))
  )
	(footprint "antmicro-footprints:C_0402_1005Metric" (layer "F.Cu")
    (at 147 110.25 90)
    (descr "Capacitor SMD 0402")
    (tags "capacitor SMD 0402")
    (property "Author" "Antmicro")
    (property "Dielectric" "X5R")
    (property "License" "Apache-2.0")
    (property "MPN" "GRM155R61H104KE14D")
    (property "Manufacturer" "Murata")
    (property "Public" "False")
    (property "Sheetfile" "channel2.kicad_sch")
    (property "Sheetname" "Channel 2")
    (property "Val" "100n")
    (property "Voltage" "50V")
    (property "ki_description" "SMD Multilayer Ceramic Capacitor, 0.1 µF, 50 V, 0402 [1005 Metric], ± 10%, X5R, GRM Series")
    (property "ki_keywords" "0402, SMT, CAPACITOR, PASSIVE, CERAMIC, MLCC")
    (attr smd)
    (fp_text reference "C38" (at -1.95 -1.5 90) (layer "F.SilkS")
        (effects (font (size 0.65 0.65) (thickness 0.13)) (justify left bottom))
    )
    (fp_text value "C_100n_0402" (at 0 1.4 90) (layer "F.Fab")
        (effects (font (size 0.65 0.65) (thickness 0.13)) (justify left bottom))
    )
    (fp_text user "License: Apache-2.0" (at -0.932 5.17 90) (layer "F.Fab") hide
        (effects (font (size 0.7 0.7) (thickness 0.15)) (justify left bottom))
    )
    (fp_text user "${REFERENCE}" (at -0.932 3.168 90) (layer "F.Fab") hide
        (effects (font (size 0.7 0.7) (thickness 0.15)) (justify left bottom))
    )
    (fp_text user "Author: Antmicro" (at -0.932 4.17 90) (layer "F.Fab") hide
        (effects (font (size 0.7 0.7) (thickness 0.15)) (justify left bottom))
    )
    (fp_rect (start -0.925 -0.47) (end 0.925 0.47)
      (stroke (width 0.05) (type default)) (fill none) (layer "F.CrtYd"))
    (fp_line (start -0.494 -0.25) (end 0.504 -0.25)
      (stroke (width 0.15) (type solid)) (layer "F.Fab"))
    (fp_line (start -0.494 0.248) (end -0.494 -0.25)
      (stroke (width 0.15) (type solid)) (layer "F.Fab"))
    (fp_line (start 0.504 -0.25) (end 0.504 0.248)
      (stroke (width 0.15) (type solid)) (layer "F.Fab"))
    (fp_line (start 0.504 0.248) (end -0.494 0.248)
      (stroke (width 0.15) (type solid)) (layer "F.Fab"))
    (pad "1" smd roundrect (at -0.48 0 90) (size 0.59 0.64) (layers "F.Cu" "F.Paste" "F.Mask") (roundrect_rratio 0.25)
      (net 2 "GND") (pintype "passive"))
    (pad "2" smd roundrect (at 0.48 0 90) (size 0.59 0.64) (layers "F.Cu" "F.Paste" "F.Mask") (roundrect_rratio 0.25)
      (net 30 "Net-(Y2-EN)") (pintype "passive"))
  )
	(footprint "antmicro-footprints:FB_0805_2012Metric" (layer "F.Cu")
    (at 142.5 115.5)
    (descr "FERRITE BEAD 0805")
    (tags "FERRITE BEAD 0805")
    (property "Author" "Antmicro")
    (property "Current" "")
    (property "License" "Apache-2.0")
    (property "MPN" "742792096")
    (property "Manufacturer" "Würth Elektronik")
    (property "Public" "False")
    (property "Sheetfile" "channel1.kicad_sch")
    (property "Sheetname" "Channel 1")
    (property "Val" "1kZ/0.8A")
    (property "ki_description" "Ferrite Beads WE-CBF 0805 100MHz 1kOhm 1A, High Current")
    (property "ki_keywords" "FERRITE BEAD, PASSIVE")
    (attr smd)
    (fp_text reference "FB4" (at -1.87 1.72) (layer "F.SilkS")
        (effects (font (size 0.65 0.65) (thickness 0.13)) (justify left bottom))
    )
    (fp_text value "FB_1kZ_0.8A_WE-CBF_0805" (at 0 1.8) (layer "F.Fab")
        (effects (font (size 0.65 0.65) (thickness 0.13)) (justify left bottom))
    )
    (fp_text user "Author: Antmicro" (at -1.9 4.4) (layer "F.Fab") hide
        (effects (font (size 0.7 0.7) (thickness 0.15)) (justify left bottom))
    )
    (fp_text user "License: Apache-2.0" (at -1.9 5.75) (layer "F.Fab") hide
        (effects (font (size 0.7 0.7) (thickness 0.15)) (justify left bottom))
    )
    (fp_text user "${REFERENCE}" (at -1.9 3.1) (layer "F.Fab") hide
        (effects (font (size 0.7 0.7) (thickness 0.15)) (justify left bottom))
    )
    (fp_line (start -0.319 0.698) (end 0.281 0.698)
      (stroke (width 0.15) (type solid)) (layer "F.SilkS"))
    (fp_line (start -0.299 -0.698) (end 0.299 -0.698)
      (stroke (width 0.15) (type solid)) (layer "F.SilkS"))
    (fp_rect (start 1.95 -0.9) (end -1.95 0.9)
      (stroke (width 0.05) (type default)) (fill none) (layer "F.CrtYd"))
    (fp_line (start -0.948 -0.681) (end 0.948 -0.681)
      (stroke (width 0.15) (type solid)) (layer "F.Fab"))
    (fp_line (start -0.948 -0.676) (end -0.948 0.676)
      (stroke (width 0.15) (type solid)) (layer "F.Fab"))
    (fp_line (start -0.948 0.681) (end 0.948 0.681)
      (stroke (width 0.15) (type solid)) (layer "F.Fab"))
    (fp_line (start 0.948 -0.676) (end 0.948 0.676)
      (stroke (width 0.15) (type solid)) (layer "F.Fab"))
    (pad "1" smd roundrect (at -1.1 0) (size 1.2 1.3) (layers "F.Cu" "F.Paste" "F.Mask") (roundrect_rratio 0.25)
      (net 7 "Net-(C10-Pad2)") (pintype "passive"))
    (pad "2" smd roundrect (at 1.1 0) (size 1.2 1.3) (layers "F.Cu" "F.Paste" "F.Mask") (roundrect_rratio 0.25)
      (net 12 "CH1_1V2") (pintype "passive"))
  )
	(footprint "antmicro-footprints:C_0402_1005Metric" (layer "F.Cu")
    (at 139.28 104.12 90)
    (descr "Capacitor SMD 0402")
    (tags "capacitor SMD 0402")
    (property "Author" "Antmicro")
    (property "Dielectric" "X5R")
    (property "License" "Apache-2.0")
    (property "MPN" "GRM155R61H104KE14D")
    (property "Manufacturer" "Murata")
    (property "Public" "False")
    (property "Sheetfile" "channel1.kicad_sch")
    (property "Sheetname" "Channel 1")
    (property "Val" "100n")
    (property "Voltage" "50V")
    (property "ki_description" "SMD Multilayer Ceramic Capacitor, 0.1 µF, 50 V, 0402 [1005 Metric], ± 10%, X5R, GRM Series")
    (property "ki_keywords" "0402, SMT, CAPACITOR, PASSIVE, CERAMIC, MLCC")
    (attr smd)
    (fp_text reference "C22" (at 5.02 -11.64 270) (layer "F.SilkS")
        (effects (font (size 0.65 0.65) (thickness 0.13)) (justify right bottom))
    )
    (fp_text value "C_100n_0402" (at 0 1.4 90) (layer "F.Fab")
        (effects (font (size 0.65 0.65) (thickness 0.13)) (justify left bottom))
    )
    (fp_text user "Author: Antmicro" (at -0.932 4.17 90) (layer "F.Fab") hide
        (effects (font (size 0.7 0.7) (thickness 0.15)) (justify left bottom))
    )
    (fp_text user "License: Apache-2.0" (at -0.932 5.17 90) (layer "F.Fab") hide
        (effects (font (size 0.7 0.7) (thickness 0.15)) (justify left bottom))
    )
    (fp_text user "${REFERENCE}" (at -0.932 3.168 90) (layer "F.Fab") hide
        (effects (font (size 0.7 0.7) (thickness 0.15)) (justify left bottom))
    )
    (fp_rect (start -0.925 -0.47) (end 0.925 0.47)
      (stroke (width 0.05) (type default)) (fill none) (layer "F.CrtYd"))
    (fp_line (start -0.494 -0.25) (end 0.504 -0.25)
      (stroke (width 0.15) (type solid)) (layer "F.Fab"))
    (fp_line (start -0.494 0.248) (end -0.494 -0.25)
      (stroke (width 0.15) (type solid)) (layer "F.Fab"))
    (fp_line (start 0.504 -0.25) (end 0.504 0.248)
      (stroke (width 0.15) (type solid)) (layer "F.Fab"))
    (fp_line (start 0.504 0.248) (end -0.494 0.248)
      (stroke (width 0.15) (type solid)) (layer "F.Fab"))
    (pad "1" smd roundrect (at -0.48 0 90) (size 0.59 0.64) (layers "F.Cu" "F.Paste" "F.Mask") (roundrect_rratio 0.25)
      (net 2 "GND") (pintype "passive"))
    (pad "2" smd roundrect (at 0.48 0 90) (size 0.59 0.64) (layers "F.Cu" "F.Paste" "F.Mask") (roundrect_rratio 0.25)
      (net 14 "+5V") (pintype "passive"))
  )
	(footprint "antmicro-footprints:C_0402_1005Metric" (layer "F.Cu")
    (at 131 110.4)
    (descr "Capacitor SMD 0402")
    (tags "capacitor SMD 0402")
    (property "Author" "Antmicro")
    (property "Dielectric" "X5R")
    (property "License" "Apache-2.0")
    (property "MPN" "GRM155R61H104KE14D")
    (property "Manufacturer" "Murata")
    (property "Public" "False")
    (property "Sheetfile" "channel1.kicad_sch")
    (property "Sheetname" "Channel 1")
    (property "Val" "100n")
    (property "Voltage" "50V")
    (property "ki_description" "SMD Multilayer Ceramic Capacitor, 0.1 µF, 50 V, 0402 [1005 Metric], ± 10%, X5R, GRM Series")
    (property "ki_keywords" "0402, SMT, CAPACITOR, PASSIVE, CERAMIC, MLCC")
    (attr smd)
    (fp_text reference "C28" (at -1.6 7.59) (layer "F.SilkS")
        (effects (font (size 0.65 0.65) (thickness 0.13)) (justify left bottom))
    )
    (fp_text value "C_100n_0402" (at 0 1.4) (layer "F.Fab")
        (effects (font (size 0.65 0.65) (thickness 0.13)) (justify left bottom))
    )
    (fp_text user "Author: Antmicro" (at -0.932 4.17) (layer "F.Fab") hide
        (effects (font (size 0.7 0.7) (thickness 0.15)) (justify left bottom))
    )
    (fp_text user "${REFERENCE}" (at -0.932 3.168) (layer "F.Fab") hide
        (effects (font (size 0.7 0.7) (thickness 0.15)) (justify left bottom))
    )
    (fp_text user "License: Apache-2.0" (at -0.932 5.17) (layer "F.Fab") hide
        (effects (font (size 0.7 0.7) (thickness 0.15)) (justify left bottom))
    )
    (fp_rect (start -0.925 -0.47) (end 0.925 0.47)
      (stroke (width 0.05) (type default)) (fill none) (layer "F.CrtYd"))
    (fp_line (start -0.494 -0.25) (end 0.504 -0.25)
      (stroke (width 0.15) (type solid)) (layer "F.Fab"))
    (fp_line (start -0.494 0.248) (end -0.494 -0.25)
      (stroke (width 0.15) (type solid)) (layer "F.Fab"))
    (fp_line (start 0.504 -0.25) (end 0.504 0.248)
      (stroke (width 0.15) (type solid)) (layer "F.Fab"))
    (fp_line (start 0.504 0.248) (end -0.494 0.248)
      (stroke (width 0.15) (type solid)) (layer "F.Fab"))
    (pad "1" smd roundrect (at -0.48 0) (size 0.59 0.64) (layers "F.Cu" "F.Paste" "F.Mask") (roundrect_rratio 0.25)
      (net 2 "GND") (pintype "passive"))
    (pad "2" smd roundrect (at 0.48 0) (size 0.59 0.64) (layers "F.Cu" "F.Paste" "F.Mask") (roundrect_rratio 0.25)
      (net 20 "Net-(U1B-VDDIO1)") (pintype "passive"))
  )
	(footprint "antmicro-footprints:C_0402_1005Metric" (layer "F.Cu")
    (at 147 105.45 -90)
    (descr "Capacitor SMD 0402")
    (tags "capacitor SMD 0402")
    (property "Author" "Antmicro")
    (property "Dielectric" "X5R")
    (property "License" "Apache-2.0")
    (property "MPN" "GRM155R61H104KE14D")
    (property "Manufacturer" "Murata")
    (property "Public" "False")
    (property "Sheetfile" "channel2.kicad_sch")
    (property "Sheetname" "Channel 2")
    (property "Val" "100n")
    (property "Voltage" "50V")
    (property "ki_description" "SMD Multilayer Ceramic Capacitor, 0.1 µF, 50 V, 0402 [1005 Metric], ± 10%, X5R, GRM Series")
    (property "ki_keywords" "0402, SMT, CAPACITOR, PASSIVE, CERAMIC, MLCC")
    (attr smd)
    (fp_text reference "C35" (at -1.15 -2.4 90) (layer "F.SilkS")
        (effects (font (size 0.65 0.65) (thickness 0.13)) (justify right bottom))
    )
    (fp_text value "C_100n_0402" (at 0 1.4 90) (layer "F.Fab")
        (effects (font (size 0.65 0.65) (thickness 0.13)) (justify right bottom))
    )
    (fp_text user "License: Apache-2.0" (at -0.932 5.17 90) (layer "F.Fab") hide
        (effects (font (size 0.7 0.7) (thickness 0.15)) (justify right bottom))
    )
    (fp_text user "${REFERENCE}" (at -0.932 3.168 90) (layer "F.Fab") hide
        (effects (font (size 0.7 0.7) (thickness 0.15)) (justify right bottom))
    )
    (fp_text user "Author: Antmicro" (at -0.932 4.17 90) (layer "F.Fab") hide
        (effects (font (size 0.7 0.7) (thickness 0.15)) (justify right bottom))
    )
    (fp_rect (start -0.925 -0.47) (end 0.925 0.47)
      (stroke (width 0.05) (type default)) (fill none) (layer "F.CrtYd"))
    (fp_line (start -0.494 -0.25) (end 0.504 -0.25)
      (stroke (width 0.15) (type solid)) (layer "F.Fab"))
    (fp_line (start -0.494 0.248) (end -0.494 -0.25)
      (stroke (width 0.15) (type solid)) (layer "F.Fab"))
    (fp_line (start 0.504 -0.25) (end 0.504 0.248)
      (stroke (width 0.15) (type solid)) (layer "F.Fab"))
    (fp_line (start 0.504 0.248) (end -0.494 0.248)
      (stroke (width 0.15) (type solid)) (layer "F.Fab"))
    (pad "1" smd roundrect (at -0.48 0 270) (size 0.59 0.64) (layers "F.Cu" "F.Paste" "F.Mask") (roundrect_rratio 0.25)
      (net 2 "GND") (pintype "passive"))
    (pad "2" smd roundrect (at 0.48 0 270) (size 0.59 0.64) (layers "F.Cu" "F.Paste" "F.Mask") (roundrect_rratio 0.25)
      (net 9 "+3V3") (pintype "passive"))
  )
	(footprint "antmicro-footprints:R_0603_1608Metric" (layer "F.Cu")
    (at 168.9 101.9)
    (descr "Resistor SMD 0603")
    (tags "resistor SMD 0603")
    (property "Author" "Antmicro")
    (property "Current" "1A")
    (property "License" "Apache-2.0")
    (property "MPN" "CR0603-J/-000ELF")
    (property "Manufacturer" "Bourns")
    (property "Public" "False")
    (property "Sheetfile" "channel2.kicad_sch")
    (property "Sheetname" "Channel 2")
    (property "Tolerance" "")
    (property "Val" "0R")
    (property "ki_description" "Zero Ohm Resistor, Jumper, 0603 [1608 Metric], Thick Film, 100 mW, 1 A, Surface Mount Device, CR")
    (property "ki_keywords" "0603, SMT, RESISTOR, PASSIVE")
    (attr smd)
    (fp_text reference "R14" (at 1 0.4) (layer "F.SilkS")
        (effects (font (size 0.7 0.7) (thickness 0.15)) (justify left bottom))
    )
    (fp_text value "R_0R_0603" (at 0 1.6) (layer "F.Fab")
        (effects (font (size 0.7 0.7) (thickness 0.15)) (justify left bottom))
    )
    (fp_text user "Author: Antmicro" (at -1.25 4.9) (layer "F.Fab") hide
        (effects (font (size 0.7 0.7) (thickness 0.15)) (justify left bottom))
    )
    (fp_text user "License: Apache-2.0" (at -1.25 5.9) (layer "F.Fab") hide
        (effects (font (size 0.7 0.7) (thickness 0.15)) (justify left bottom))
    )
    (fp_text user "${REFERENCE}" (at -1.25 3.898) (layer "F.Fab") hide
        (effects (font (size 0.7 0.7) (thickness 0.15)) (justify left bottom))
    )
    (fp_line (start -0.15 -0.4) (end 0.15 -0.4)
      (stroke (width 0.15) (type solid)) (layer "F.SilkS"))
    (fp_line (start -0.15 0.4) (end 0.15 0.4)
      (stroke (width 0.15) (type solid)) (layer "F.SilkS"))
    (fp_rect (start -1.25 -0.65) (end 1.25 0.65)
      (stroke (width 0.05) (type solid)) (fill none) (layer "F.CrtYd"))
    (fp_rect (start -0.8 -0.4) (end 0.8 0.4)
      (stroke (width 0.15) (type solid)) (fill none) (layer "F.Fab"))
    (pad "1" smd roundrect (at -0.7 0) (size 0.8 1) (layers "F.Cu" "F.Paste" "F.Mask") (roundrect_rratio 0.2)
      (net 96 "/Channel 2/HDMI2_POWER") (pintype "passive"))
    (pad "2" smd roundrect (at 0.7 0) (size 0.8 1) (layers "F.Cu" "F.Paste" "F.Mask") (roundrect_rratio 0.2)
      (net 141 "/Channel 2/HDMI2_HPD") (pintype "passive"))
  )
)
